# T6G (Grand Teton) — schematic netlist excerpt (pin names and nets, part order shuffled) for the footprints in the layout excerpt that follows; sources: Cadence DE-HDL packaged netlist, KiCad conversion of 04192023_DAF0TMB3IC0_F0TG_MB_C_brd_V02_OCP.brd

C649  Q_CAP  4.7UF 6.3V 20% X6S  pkg 0402  page 290 : A = P0V9_CPU0_RT1_2A ; B = GND
R441  Q_RES  2.2K 5% CHIP  pkg 0402LF  page 28 : A = CPU0_NMI_SYNC_FLOOD_N ; B = PVDD18_S5_P0

(kicad_pcb
	(version 20260206)
	(generator "pcbnew")
	(generator_version "10.0")
	(general
		(thickness 1.6)
		(legacy_teardrops no)
	)
	(paper "A4")
	(title_block
		(title "04192023_DAF0TMB3IC0_F0TG_MB_C_brd_V02_OCP.brd")
		(comment 1 "Grand Teton / footprints 5307-5308 of 8354")
	)
	(layers
		(0 "F.Cu" signal "TOP")
		(4 "In1.Cu" signal "GND")
		(6 "In2.Cu" signal "IN1")
		(8 "In3.Cu" signal "GND1")
		(10 "In4.Cu" signal "IN2")
		(12 "In5.Cu" signal "GND2")
		(14 "In6.Cu" signal "IN3")
		(16 "In7.Cu" signal "GND3")
		(18 "In8.Cu" signal "VCC")
		(20 "In9.Cu" signal "VCC1")
		(22 "In10.Cu" signal "GND4")
		(24 "In11.Cu" signal "IN4")
		(26 "In12.Cu" signal "GND5")
		(28 "In13.Cu" signal "IN5")
		(30 "In14.Cu" signal "GND6")
		(32 "In15.Cu" signal "IN6")
		(34 "In16.Cu" signal "GND7")
		(2 "B.Cu" signal "BOTTOM")
		(9 "F.Adhes" user "F.Adhesive")
		(11 "B.Adhes" user "B.Adhesive")
		(13 "F.Paste" user "Package Geometry/Pastemask Top")
		(15 "B.Paste" user "Package Geometry/Pastemask Bottom")
		(5 "F.SilkS" user "Ref Des/Silkscreen Top")
		(7 "B.SilkS" user "Ref Des/Silkscreen Bottom")
		(1 "F.Mask" user "Board Geometry/Soldermask Top")
		(3 "B.Mask" user "Board Geometry/Soldermask Bottom")
		(17 "Dwgs.User" user "User.Drawings")
		(19 "Cmts.User" user "User.Comments")
		(21 "Eco1.User" user "User.Eco1")
		(23 "Eco2.User" user "User.Eco2")
		(25 "Edge.Cuts" user "Board Geometry/Outline")
		(27 "Margin" user)
		(31 "F.CrtYd" user "Package Geometry/Place Bound Top")
		(29 "B.CrtYd" user "Package Geometry/Place Bound Bottom")
		(35 "F.Fab" user "Ref Des/Assembly Top")
		(33 "B.Fab" user "Ref Des/Assembly Bottom")
	)
	(footprint ""
		(layer "B.Cu")
		(at 335.014824 -399.722848 -90)
		(property "Reference" "C649"
			(at 0 0 90)
			(layer "B.SilkS")
			(hide yes)
			(effects
				(font
					(size 1.27 1.27)
				)
				(justify mirror)
			)
		)
		(property "Value" ""
			(at 0 0 90)
			(layer "B.Fab")
			(effects
				(font
					(size 1.27 1.27)
				)
				(justify mirror)
			)
		)
		(duplicate_pad_numbers_are_jumpers no)
		(fp_line
			(start -0.7874 0.4064)
			(end 0.7874 0.4064)
			(stroke
				(width 0.1524)
				(type default)
			)
			(layer "B.SilkS")
		)
		(fp_line
			(start 0.7874 0.4064)
			(end 0.7874 -0.4064)
			(stroke
				(width 0.1524)
				(type default)
			)
			(layer "B.SilkS")
		)
		(fp_line
			(start -0.7874 -0.4064)
			(end -0.7874 0.4064)
			(stroke
				(width 0.1524)
				(type default)
			)
			(layer "B.SilkS")
		)
		(fp_line
			(start 0.7874 -0.4064)
			(end -0.7874 -0.4064)
			(stroke
				(width 0.1524)
				(type default)
			)
			(layer "B.SilkS")
		)
		(fp_line
			(start -0.67945 0.3048)
			(end -0.120396 0.3048)
			(stroke
				(width 0.1)
				(type default)
			)
			(layer "B.Fab")
		)
		(fp_line
			(start -0.120396 0.3048)
			(end -0.120396 0.2794)
			(stroke
				(width 0.1)
				(type default)
			)
			(layer "B.Fab")
		)
		(fp_line
			(start 0.12065 0.3048)
			(end 0.67945 0.3048)
			(stroke
				(width 0.1)
				(type default)
			)
			(layer "B.Fab")
		)
		(fp_line
			(start 0.67945 0.3048)
			(end 0.67945 -0.305054)
			(stroke
				(width 0.1)
				(type default)
			)
			(layer "B.Fab")
		)
		(fp_line
			(start -0.120396 0.2794)
			(end 0.12065 0.2794)
			(stroke
				(width 0.1)
				(type default)
			)
			(layer "B.Fab")
		)
		(fp_line
			(start 0.12065 0.2794)
			(end 0.12065 0.3048)
			(stroke
				(width 0.1)
				(type default)
			)
			(layer "B.Fab")
		)
		(fp_line
			(start -0.12065 -0.2794)
			(end -0.12065 -0.3048)
			(stroke
				(width 0.1)
				(type default)
			)
			(layer "B.Fab")
		)
		(fp_line
			(start 0.12065 -0.2794)
			(end -0.12065 -0.2794)
			(stroke
				(width 0.1)
				(type default)
			)
			(layer "B.Fab")
		)
		(fp_line
			(start -0.67945 -0.3048)
			(end -0.67945 0.3048)
			(stroke
				(width 0.1)
				(type default)
			)
			(layer "B.Fab")
		)
		(fp_line
			(start -0.12065 -0.3048)
			(end -0.67945 -0.3048)
			(stroke
				(width 0.1)
				(type default)
			)
			(layer "B.Fab")
		)
		(fp_line
			(start 0.12065 -0.305054)
			(end 0.12065 -0.2794)
			(stroke
				(width 0.1)
				(type default)
			)
			(layer "B.Fab")
		)
		(fp_line
			(start 0.67945 -0.305054)
			(end 0.12065 -0.305054)
			(stroke
				(width 0.1)
				(type default)
			)
			(layer "B.Fab")
		)
		(pad "1" smd circle
			(at 0.40005 0 90)
			(size 0 0)
			(layers "B.Cu" "B.Mask" "B.Paste")
			(net "P0V9_CPU0_RT1_2A")
		)
		(pad "2" smd circle
			(at -0.40005 0 90)
			(size 0 0)
			(layers "B.Cu" "B.Mask" "B.Paste")
			(net "GND")
		)
	)
	(footprint ""
		(layer "B.Cu")
		(at 401.11807 -331.360526 90)
		(property "Reference" "R441"
			(at 0 0 90)
			(layer "B.SilkS")
			(hide yes)
			(effects
				(font
					(size 1.27 1.27)
				)
				(justify mirror)
			)
		)
		(property "Value" ""
			(at 0 0 90)
			(layer "B.Fab")
			(effects
				(font
					(size 1.27 1.27)
				)
				(justify mirror)
			)
		)
		(duplicate_pad_numbers_are_jumpers no)
		(fp_line
			(start 0.7874 -0.4064)
			(end -0.7874 -0.4064)
			(stroke
				(width 0.1524)
				(type default)
			)
			(layer "B.SilkS")
		)
		(fp_line
			(start -0.7874 -0.4064)
			(end -0.7874 0.4064)
			(stroke
				(width 0.1524)
				(type default)
			)
			(layer "B.SilkS")
		)
		(fp_line
			(start 0.7874 0.4064)
			(end 0.7874 -0.4064)
			(stroke
				(width 0.1524)
				(type default)
			)
			(layer "B.SilkS")
		)
		(fp_line
			(start -0.7874 0.4064)
			(end 0.7874 0.4064)
			(stroke
				(width 0.1524)
				(type default)
			)
			(layer "B.SilkS")
		)
		(fp_line
			(start 0.67945 -0.305054)
			(end 0.12065 -0.305054)
			(stroke
				(width 0.1)
				(type default)
			)
			(layer "B.Fab")
		)
		(fp_line
			(start 0.12065 -0.305054)
			(end 0.12065 -0.2794)
			(stroke
				(width 0.1)
				(type default)
			)
			(layer "B.Fab")
		)
		(fp_line
			(start -0.12065 -0.3048)
			(end -0.67945 -0.3048)
			(stroke
				(width 0.1)
				(type default)
			)
			(layer "B.Fab")
		)
		(fp_line
			(start -0.67945 -0.3048)
			(end -0.67945 0.3048)
			(stroke
				(width 0.1)
				(type default)
			)
			(layer "B.Fab")
		)
		(fp_line
			(start 0.12065 -0.2794)
			(end -0.12065 -0.2794)
			(stroke
				(width 0.1)
				(type default)
			)
			(layer "B.Fab")
		)
		(fp_line
			(start -0.12065 -0.2794)
			(end -0.12065 -0.3048)
			(stroke
				(width 0.1)
				(type default)
			)
			(layer "B.Fab")
		)
		(fp_line
			(start 0.12065 0.2794)
			(end 0.12065 0.3048)
			(stroke
				(width 0.1)
				(type default)
			)
			(layer "B.Fab")
		)
		(fp_line
			(start -0.120396 0.2794)
			(end 0.12065 0.2794)
			(stroke
				(width 0.1)
				(type default)
			)
			(layer "B.Fab")
		)
		(fp_line
			(start 0.67945 0.3048)
			(end 0.67945 -0.305054)
			(stroke
				(width 0.1)
				(type default)
			)
			(layer "B.Fab")
		)
		(fp_line
			(start 0.12065 0.3048)
			(end 0.67945 0.3048)
			(stroke
				(width 0.1)
				(type default)
			)
			(layer "B.Fab")
		)
		(fp_line
			(start -0.120396 0.3048)
			(end -0.120396 0.2794)
			(stroke
				(width 0.1)
				(type default)
			)
			(layer "B.Fab")
		)
		(fp_line
			(start -0.67945 0.3048)
			(end -0.120396 0.3048)
			(stroke
				(width 0.1)
				(type default)
			)
			(layer "B.Fab")
		)
		(pad "1" smd circle
			(at 0.40005 0 270)
			(size 0 0)
			(layers "B.Cu" "B.Mask" "B.Paste")
			(net "CPU0_NMI_SYNC_FLOOD_N")
		)
		(pad "2" smd circle
			(at -0.40005 0 270)
			(size 0 0)
			(layers "B.Cu" "B.Mask" "B.Paste")
			(net "PVDD18_S5_P0")
		)
	)
)
